(kicad_pcb
	(version 20241229)
	(generator "pcbnew")
	(generator_version "9.0")
	(general
		(thickness 1.711)
		(legacy_teardrops no)
	)
	(paper "A4")
	(title_block
		(title "Antmicro Baseboard for Jetson AGX Thor")
		(date "2026-02-18")
		(rev "1.1.0")
		(company "Antmicro Ltd")
		(comment 1 "www.antmicro.com")
		(comment 9 "footprints 201-204 of 1170")
	)
	(layers
		(0 "F.Cu" signal)
		(4 "In1.Cu" signal)
		(6 "In2.Cu" signal)
		(8 "In3.Cu" signal)
		(10 "In4.Cu" jumper)
		(12 "In5.Cu" signal)
		(14 "In6.Cu" signal)
		(16 "In7.Cu" signal)
		(18 "In8.Cu" signal)
		(2 "B.Cu" signal)
		(9 "F.Adhes" user "F.Adhesive")
		(11 "B.Adhes" user "B.Adhesive")
		(13 "F.Paste" user)
		(15 "B.Paste" user)
		(5 "F.SilkS" user "F.Silkscreen")
		(7 "B.SilkS" user "B.Silkscreen")
		(1 "F.Mask" user)
		(3 "B.Mask" user)
		(17 "Dwgs.User" user "User.Drawings")
		(19 "Cmts.User" user "User.Comments")
		(21 "Eco1.User" user "User.Eco1")
		(23 "Eco2.User" user "User.Eco2")
		(25 "Edge.Cuts" user)
		(27 "Margin" user)
		(31 "F.CrtYd" user "F.Courtyard")
		(29 "B.CrtYd" user "B.Courtyard")
		(35 "F.Fab" user)
		(33 "B.Fab" user)
	)
	(footprint "antmicro-footprints:SOT-523"
		(layer "F.Cu")
		(at 140.89 131.15 -90)
		(property "Reference" "Q40"
			(at -2 -1.08 180)
			(layer "F.SilkS")
			(effects
				(font
					(size 0.7 0.7)
					(thickness 0.15)
				)
				(justify right top)
			)
		)
		(property "Value" "DMG1012T-7"
			(at 0.1 1.824 90)
			(layer "F.Fab")
			(effects
				(font
					(size 0.7 0.7)
					(thickness 0.15)
				)
				(justify right top)
			)
		)
		(property "Datasheet" "https://www.diodes.com/assets/Datasheets/ds31783.pdf"
			(at 0 0 90)
			(layer "F.Fab")
			(hide yes)
			(effects
				(font
					(size 1.27 1.27)
					(thickness 0.15)
				)
			)
		)
		(property "Description" "Power MOSFET, N Channel, 20 V, 630 mA, 0.3 ohm, SOT-523, Surface Mount"
			(at 0 0 90)
			(layer "F.Fab")
			(hide yes)
			(effects
				(font
					(size 1.27 1.27)
					(thickness 0.15)
				)
			)
		)
		(property "MPN" "DMG1012T-7"
			(at 0 0 270)
			(unlocked yes)
			(layer "F.Fab")
			(hide yes)
			(effects
				(font
					(size 1 1)
					(thickness 0.15)
				)
			)
		)
		(property "Manufacturer" "Diodes Incorporated"
			(at 0 0 270)
			(unlocked yes)
			(layer "F.Fab")
			(hide yes)
			(effects
				(font
					(size 1 1)
					(thickness 0.15)
				)
			)
		)
		(property "Author" "Antmicro"
			(at 0 0 270)
			(unlocked yes)
			(layer "F.Fab")
			(hide yes)
			(effects
				(font
					(size 1 1)
					(thickness 0.15)
				)
			)
		)
		(property "License" "Apache-2.0"
			(at 0 0 270)
			(unlocked yes)
			(layer "F.Fab")
			(hide yes)
			(effects
				(font
					(size 1 1)
					(thickness 0.15)
				)
			)
		)
		(sheetname "/SoM_Power/")
		(sheetfile "som_power.kicad_sch")
		(attr smd)
		(fp_line
			(start -0.927 -0.051)
			(end -0.927 -0.351)
			(stroke
				(width 0.15)
				(type solid)
			)
			(layer "F.SilkS")
		)
		(fp_line
			(start -0.927 -0.351)
			(end -0.725 -0.551)
			(stroke
				(width 0.15)
				(type solid)
			)
			(layer "F.SilkS")
		)
		(fp_line
			(start -0.725 -0.551)
			(end -0.277 -0.551)
			(stroke
				(width 0.15)
				(type solid)
			)
			(layer "F.SilkS")
		)
		(fp_line
			(start -0.277 -0.551)
			(end -0.277 -0.75)
			(stroke
				(width 0.15)
				(type solid)
			)
			(layer "F.SilkS")
		)
		(fp_circle
			(center -0.9652 0.9652)
			(end -0.9152 0.9652)
			(stroke
				(width 0.15)
				(type solid)
			)
			(fill yes)
			(layer "F.SilkS")
		)
		(fp_line
			(start -1.12 1.15)
			(end 1.1 1.15)
			(stroke
				(width 0.05)
				(type solid)
			)
			(layer "F.CrtYd")
		)
		(fp_line
			(start -1.12 -1.16)
			(end -1.12 1.15)
			(stroke
				(width 0.05)
				(type solid)
			)
			(layer "F.CrtYd")
		)
		(fp_line
			(start -1.12 -1.16)
			(end 1.1 -1.16)
			(stroke
				(width 0.05)
				(type solid)
			)
			(layer "F.CrtYd")
		)
		(fp_line
			(start 1.1 -1.16)
			(end 1.1 1.15)
			(stroke
				(width 0.05)
				(type solid)
			)
			(layer "F.CrtYd")
		)
		(fp_line
			(start 0.8 0.424)
			(end -0.802 0.424)
			(stroke
				(width 0.15)
				(type solid)
			)
			(layer "F.Fab")
		)
		(fp_line
			(start -0.802 -0.276)
			(end -0.802 0.424)
			(stroke
				(width 0.15)
				(type solid)
			)
			(layer "F.Fab")
		)
		(fp_line
			(start -0.652 -0.425)
			(end -0.802 -0.276)
			(stroke
				(width 0.15)
				(type solid)
			)
			(layer "F.Fab")
		)
		(fp_line
			(start 0.8 -0.425)
			(end 0.8 0.424)
			(stroke
				(width 0.15)
				(type solid)
			)
			(layer "F.Fab")
		)
		(fp_line
			(start 0.8 -0.425)
			(end -0.652 -0.425)
			(stroke
				(width 0.15)
				(type solid)
			)
			(layer "F.Fab")
		)
		(fp_circle
			(center -0.9652 0.9652)
			(end -0.9144 0.9652)
			(stroke
				(width 0.15)
				(type solid)
			)
			(fill no)
			(layer "F.Fab")
		)
		(fp_text user "License: Apache-2.0"
			(at -1.12 5.024 90)
			(layer "F.Fab")
			(effects
				(font
					(size 0.7 0.7)
					(thickness 0.15)
				)
				(justify right top)
			)
		)
		(fp_text user "${REFERENCE}"
			(at -1.12 3.824 90)
			(layer "F.Fab")
			(effects
				(font
					(size 0.7 0.7)
					(thickness 0.15)
				)
				(justify right top)
			)
		)
		(fp_text user "Author: Antmicro"
			(at -1.12 6.224 90)
			(layer "F.Fab")
			(effects
				(font
					(size 0.7 0.7)
					(thickness 0.15)
				)
				(justify right top)
			)
		)
		(pad "1" smd rect
			(at -0.5 0.65 270)
			(size 0.4 0.51)
			(layers "F.Cu" "F.Mask" "F.Paste")
			(net 1293 "/DCDC/CARRIER_PWR_ON")
			(pinfunction "G")
			(pintype "input")
		)
		(pad "2" smd rect
			(at 0.498 0.65 270)
			(size 0.4 0.51)
			(layers "F.Cu" "F.Mask" "F.Paste")
			(net 1 "GND")
			(pinfunction "S")
			(pintype "passive")
		)
		(pad "3" smd rect
			(at 0 -0.652 270)
			(size 0.4 0.51)
			(layers "F.Cu" "F.Mask" "F.Paste")
			(net 883 "Net-(Q10-G)")
			(pinfunction "D")
			(pintype "passive")
		)
	)
	(footprint "antmicro-footprints:C_0402_1005Metric"
		(layer "F.Cu")
		(at 89.1 101.6 180)
		(descr "Capacitor SMD 0402")
		(tags "capacitor SMD 0402")
		(property "Reference" "C352"
			(at 3.8 -0.4 180)
			(layer "F.SilkS")
			(effects
				(font
					(size 0.7 0.7)
					(thickness 0.15)
				)
				(justify left bottom)
			)
		)
		(property "Value" "C_100n_0402"
			(at -1.022927 2.155213 180)
			(layer "F.Fab")
			(effects
				(font
					(size 0.7 0.7)
					(thickness 0.15)
				)
				(justify left bottom)
			)
		)
		(property "Datasheet" "https://www.murata.com/products/productdetail?partno=GRM155R61H104KE14%23"
			(at 0 0 180)
			(layer "F.Fab")
			(hide yes)
			(effects
				(font
					(size 1.27 1.27)
					(thickness 0.15)
				)
			)
		)
		(property "Description" "SMD Multilayer Ceramic Capacitor, 0.1 µF, 50 V, 0402 [1005 Metric], ± 10%, X5R, GRM Series"
			(at 0 0 180)
			(layer "F.Fab")
			(hide yes)
			(effects
				(font
					(size 1.27 1.27)
					(thickness 0.15)
				)
			)
		)
		(property "Manufacturer" "Murata"
			(at 0 0 180)
			(unlocked yes)
			(layer "F.Fab")
			(hide yes)
			(effects
				(font
					(size 1 1)
					(thickness 0.15)
				)
			)
		)
		(property "MPN" "GRM155R61H104KE14D"
			(at 0 0 180)
			(unlocked yes)
			(layer "F.Fab")
			(hide yes)
			(effects
				(font
					(size 1 1)
					(thickness 0.15)
				)
			)
		)
		(property "Val" "100n"
			(at 0 0 180)
			(unlocked yes)
			(layer "F.Fab")
			(hide yes)
			(effects
				(font
					(size 1 1)
					(thickness 0.15)
				)
			)
		)
		(property "License" "Apache-2.0"
			(at 0 0 180)
			(unlocked yes)
			(layer "F.Fab")
			(hide yes)
			(effects
				(font
					(size 1 1)
					(thickness 0.15)
				)
			)
		)
		(property "Author" "Antmicro"
			(at 0 0 180)
			(unlocked yes)
			(layer "F.Fab")
			(hide yes)
			(effects
				(font
					(size 1 1)
					(thickness 0.15)
				)
			)
		)
		(property "Voltage" "50V"
			(at 0 0 180)
			(unlocked yes)
			(layer "F.Fab")
			(hide yes)
			(effects
				(font
					(size 1 1)
					(thickness 0.15)
				)
			)
		)
		(property "Dielectric" "X5R"
			(at 0 0 180)
			(unlocked yes)
			(layer "F.Fab")
			(hide yes)
			(effects
				(font
					(size 1 1)
					(thickness 0.15)
				)
			)
		)
		(sheetname "/SoM_IO2/")
		(sheetfile "som_io2.kicad_sch")
		(attr smd)
		(fp_poly
			(pts
				(xy -0.925 -0.47) (xy 0.925 -0.47) (xy 0.925 0.47) (xy -0.925 0.47)
			)
			(stroke
				(width 0.05)
				(type default)
			)
			(fill no)
			(layer "F.CrtYd")
		)
		(fp_line
			(start 0.504 0.248)
			(end -0.494 0.248)
			(stroke
				(width 0.15)
				(type solid)
			)
			(layer "F.Fab")
		)
		(fp_line
			(start 0.504 -0.25)
			(end 0.504 0.248)
			(stroke
				(width 0.15)
				(type solid)
			)
			(layer "F.Fab")
		)
		(fp_line
			(start -0.494 0.248)
			(end -0.494 -0.25)
			(stroke
				(width 0.15)
				(type solid)
			)
			(layer "F.Fab")
		)
		(fp_line
			(start -0.494 -0.25)
			(end 0.504 -0.25)
			(stroke
				(width 0.15)
				(type solid)
			)
			(layer "F.Fab")
		)
		(fp_text user "Author: Antmicro"
			(at -0.939 3.399 180)
			(layer "F.Fab")
			(effects
				(font
					(size 0.7 0.7)
					(thickness 0.15)
				)
				(justify left bottom)
			)
		)
		(fp_text user "License: Apache-2.0"
			(at -0.939 5.799 180)
			(layer "F.Fab")
			(effects
				(font
					(size 0.7 0.7)
					(thickness 0.15)
				)
				(justify left bottom)
			)
		)
		(fp_text user "${REFERENCE}"
			(at -0.939 4.599 180)
			(layer "F.Fab")
			(effects
				(font
					(size 0.7 0.7)
					(thickness 0.15)
				)
				(justify left bottom)
			)
		)
		(pad "1" smd roundrect
			(at -0.48 0 180)
			(size 0.59 0.64)
			(layers "F.Cu" "F.Mask" "F.Paste")
			(roundrect_rratio 0.25)
			(net 1272 "/SoM_IO2/DP3.AUX_C+")
			(pintype "passive")
		)
		(pad "2" smd roundrect
			(at 0.48 0 180)
			(size 0.59 0.64)
			(layers "F.Cu" "F.Mask" "F.Paste")
			(roundrect_rratio 0.25)
			(net 776 "/Expansion connector/DP3.AUX+")
			(pintype "passive")
		)
	)
	(footprint "antmicro-footprints:C_0402_1005Metric"
		(layer "F.Cu")
		(at 66.6 92.7 180)
		(descr "Capacitor SMD 0402")
		(tags "capacitor SMD 0402")
		(property "Reference" "C165"
			(at -1.1 -0.4 180)
			(layer "F.SilkS")
			(effects
				(font
					(size 0.7 0.7)
					(thickness 0.15)
				)
				(justify left bottom)
			)
		)
		(property "Value" "C_1u_0402"
			(at -1.022927 2.155213 180)
			(layer "F.Fab")
			(effects
				(font
					(size 0.7 0.7)
					(thickness 0.15)
				)
				(justify left bottom)
			)
		)
		(property "Datasheet" "https://product.tdk.com/en/search/capacitor/ceramic/mlcc/info?part_no=C1005X6S1A105K050BC"
			(at 0 0 180)
			(layer "F.Fab")
			(hide yes)
			(effects
				(font
					(size 1.27 1.27)
					(thickness 0.15)
				)
			)
		)
		(property "Description" "SMD Multilayer Ceramic Capacitor, 1 µF, 10 V, 0402 [1005 Metric], ± 10%, X6S, C"
			(at 0 0 180)
			(layer "F.Fab")
			(hide yes)
			(effects
				(font
					(size 1.27 1.27)
					(thickness 0.15)
				)
			)
		)
		(property "Manufacturer" "TDK"
			(at 0 0 180)
			(unlocked yes)
			(layer "F.Fab")
			(hide yes)
			(effects
				(font
					(size 1 1)
					(thickness 0.15)
				)
			)
		)
		(property "MPN" "C1005X6S1A105K050BC"
			(at 0 0 180)
			(unlocked yes)
			(layer "F.Fab")
			(hide yes)
			(effects
				(font
					(size 1 1)
					(thickness 0.15)
				)
			)
		)
		(property "Val" "1u"
			(at 0 0 180)
			(unlocked yes)
			(layer "F.Fab")
			(hide yes)
			(effects
				(font
					(size 1 1)
					(thickness 0.15)
				)
			)
		)
		(property "License" "Apache-2.0"
			(at 0 0 180)
			(unlocked yes)
			(layer "F.Fab")
			(hide yes)
			(effects
				(font
					(size 1 1)
					(thickness 0.15)
				)
			)
		)
		(property "Author" "Antmicro"
			(at 0 0 180)
			(unlocked yes)
			(layer "F.Fab")
			(hide yes)
			(effects
				(font
					(size 1 1)
					(thickness 0.15)
				)
			)
		)
		(property "Voltage" ""
			(at 0 0 180)
			(unlocked yes)
			(layer "F.Fab")
			(hide yes)
			(effects
				(font
					(size 1 1)
					(thickness 0.15)
				)
			)
		)
		(property "Dielectric" ""
			(at 0 0 180)
			(unlocked yes)
			(layer "F.Fab")
			(hide yes)
			(effects
				(font
					(size 1 1)
					(thickness 0.15)
				)
			)
		)
		(sheetname "/CSI/")
		(sheetfile "csi.kicad_sch")
		(attr smd)
		(fp_rect
			(start -0.925 -0.47)
			(end 0.925 0.47)
			(stroke
				(width 0.05)
				(type default)
			)
			(fill no)
			(layer "F.CrtYd")
		)
		(fp_line
			(start 0.504 0.248)
			(end -0.494 0.248)
			(stroke
				(width 0.15)
				(type solid)
			)
			(layer "F.Fab")
		)
		(fp_line
			(start 0.504 -0.25)
			(end 0.504 0.248)
			(stroke
				(width 0.15)
				(type solid)
			)
			(layer "F.Fab")
		)
		(fp_line
			(start -0.494 0.248)
			(end -0.494 -0.25)
			(stroke
				(width 0.15)
				(type solid)
			)
			(layer "F.Fab")
		)
		(fp_line
			(start -0.494 -0.25)
			(end 0.504 -0.25)
			(stroke
				(width 0.15)
				(type solid)
			)
			(layer "F.Fab")
		)
		(fp_text user "License: Apache-2.0"
			(at -0.939 5.799 180)
			(layer "F.Fab")
			(effects
				(font
					(size 0.7 0.7)
					(thickness 0.15)
				)
				(justify left bottom)
			)
		)
		(fp_text user "Author: Antmicro"
			(at -0.939 3.399 180)
			(layer "F.Fab")
			(effects
				(font
					(size 0.7 0.7)
					(thickness 0.15)
				)
				(justify left bottom)
			)
		)
		(fp_text user "${REFERENCE}"
			(at -0.939 4.599 180)
			(layer "F.Fab")
			(effects
				(font
					(size 0.7 0.7)
					(thickness 0.15)
				)
				(justify left bottom)
			)
		)
		(pad "1" smd roundrect
			(at -0.48 0 180)
			(size 0.59 0.64)
			(layers "F.Cu" "F.Mask" "F.Paste")
			(roundrect_rratio 0.25)
			(net 1 "GND")
			(pintype "passive")
		)
		(pad "2" smd roundrect
			(at 0.48 0 180)
			(size 0.59 0.64)
			(layers "F.Cu" "F.Mask" "F.Paste")
			(roundrect_rratio 0.25)
			(net 7 "/CSI/CSIA_5V")
			(pintype "passive")
		)
	)
	(footprint "antmicro-footprints:C_0402_1005Metric"
		(layer "F.Cu")
		(at 63.9 98 90)
		(descr "Capacitor SMD 0402")
		(tags "capacitor SMD 0402")
		(property "Reference" "C166"
			(at -1.6 -0.6 90)
			(layer "F.SilkS")
			(effects
				(font
					(size 0.7 0.7)
					(thickness 0.15)
				)
				(justify left bottom)
			)
		)
		(property "Value" "C_100n_0402"
			(at -1.022927 2.155213 90)
			(layer "F.Fab")
			(effects
				(font
					(size 0.7 0.7)
					(thickness 0.15)
				)
				(justify left bottom)
			)
		)
		(property "Datasheet" "https://www.murata.com/products/productdetail?partno=GRM155R61H104KE14%23"
			(at 0 0 90)
			(layer "F.Fab")
			(hide yes)
			(effects
				(font
					(size 1.27 1.27)
					(thickness 0.15)
				)
			)
		)
		(property "Description" "SMD Multilayer Ceramic Capacitor, 0.1 µF, 50 V, 0402 [1005 Metric], ± 10%, X5R, GRM Series"
			(at 0 0 90)
			(layer "F.Fab")
			(hide yes)
			(effects
				(font
					(size 1.27 1.27)
					(thickness 0.15)
				)
			)
		)
		(property "Manufacturer" "Murata"
			(at 0 0 90)
			(unlocked yes)
			(layer "F.Fab")
			(hide yes)
			(effects
				(font
					(size 1 1)
					(thickness 0.15)
				)
			)
		)
		(property "MPN" "GRM155R61H104KE14D"
			(at 0 0 90)
			(unlocked yes)
			(layer "F.Fab")
			(hide yes)
			(effects
				(font
					(size 1 1)
					(thickness 0.15)
				)
			)
		)
		(property "Val" "100n"
			(at 0 0 90)
			(unlocked yes)
			(layer "F.Fab")
			(hide yes)
			(effects
				(font
					(size 1 1)
					(thickness 0.15)
				)
			)
		)
		(property "License" "Apache-2.0"
			(at 0 0 90)
			(unlocked yes)
			(layer "F.Fab")
			(hide yes)
			(effects
				(font
					(size 1 1)
					(thickness 0.15)
				)
			)
		)
		(property "Author" "Antmicro"
			(at 0 0 90)
			(unlocked yes)
			(layer "F.Fab")
			(hide yes)
			(effects
				(font
					(size 1 1)
					(thickness 0.15)
				)
			)
		)
		(property "Voltage" "50V"
			(at 0 0 90)
			(unlocked yes)
			(layer "F.Fab")
			(hide yes)
			(effects
				(font
					(size 1 1)
					(thickness 0.15)
				)
			)
		)
		(property "Dielectric" "X5R"
			(at 0 0 90)
			(unlocked yes)
			(layer "F.Fab")
			(hide yes)
			(effects
				(font
					(size 1 1)
					(thickness 0.15)
				)
			)
		)
		(sheetname "/CSI/")
		(sheetfile "csi.kicad_sch")
		(attr smd)
		(fp_poly
			(pts
				(xy -0.925 -0.47) (xy -0.925 0.47) (xy 0.925 0.47) (xy 0.925 -0.47)
			)
			(stroke
				(width 0.05)
				(type default)
			)
			(fill no)
			(layer "F.CrtYd")
		)
		(fp_line
			(start 0.504 -0.25)
			(end 0.504 0.248)
			(stroke
				(width 0.15)
				(type solid)
			)
			(layer "F.Fab")
		)
		(fp_line
			(start -0.494 -0.25)
			(end 0.504 -0.25)
			(stroke
				(width 0.15)
				(type solid)
			)
			(layer "F.Fab")
		)
		(fp_line
			(start 0.504 0.248)
			(end -0.494 0.248)
			(stroke
				(width 0.15)
				(type solid)
			)
			(layer "F.Fab")
		)
		(fp_line
			(start -0.494 0.248)
			(end -0.494 -0.25)
			(stroke
				(width 0.15)
				(type solid)
			)
			(layer "F.Fab")
		)
		(fp_text user "License: Apache-2.0"
			(at -0.939 5.799 90)
			(layer "F.Fab")
			(effects
				(font
					(size 0.7 0.7)
					(thickness 0.15)
				)
				(justify left bottom)
			)
		)
		(fp_text user "Author: Antmicro"
			(at -0.939 3.399 90)
			(layer "F.Fab")
			(effects
				(font
					(size 0.7 0.7)
					(thickness 0.15)
				)
				(justify left bottom)
			)
		)
		(fp_text user "${REFERENCE}"
			(at -0.939 4.599 90)
			(layer "F.Fab")
			(effects
				(font
					(size 0.7 0.7)
					(thickness 0.15)
				)
				(justify left bottom)
			)
		)
		(pad "1" smd roundrect
			(at -0.48 0 90)
			(size 0.59 0.64)
			(layers "F.Cu" "F.Mask" "F.Paste")
			(roundrect_rratio 0.25)
			(net 1 "GND")
			(pintype "passive")
		)
		(pad "2" smd roundrect
			(at 0.48 0 90)
			(size 0.59 0.64)
			(layers "F.Cu" "F.Mask" "F.Paste")
			(roundrect_rratio 0.25)
			(net 2 "+3V3")
			(pintype "passive")
		)
	)
)
